# S9S_MB_2U (Grand Teton) — schematic netlist excerpt (pin names and nets, part order shuffled) for the footprints in the layout excerpt that follows; sources: Cadence DE-HDL packaged netlist, KiCad conversion of 03242023_DA0F0TMBIJ0_F0T_Motherboard_J_brd_V01_OCP.brd

R735  Q_RES  10K 1% CHIP  pkg 0402LF  page 220 : A = P3V3_AUX ; B = FM_DIMM_12V_CPS_SX_N
C982  Q_CAP  10UF 6.3V 20% X6S  pkg C0402  page 74 : A = PVCCIN_CPU0 ; B = GND

(kicad_pcb
	(version 20260206)
	(generator "pcbnew")
	(generator_version "10.0")
	(general
		(thickness 1.6)
		(legacy_teardrops no)
	)
	(paper "A4")
	(title_block
		(title "03242023_DA0F0TMBIJ0_F0T_Motherboard_J_brd_V01_OCP.brd")
		(comment 1 "Grand Teton / footprints 1817-1818 of 6105")
	)
	(layers
		(0 "F.Cu" signal "TOP")
		(4 "In1.Cu" signal "GND")
		(6 "In2.Cu" signal "IN1")
		(8 "In3.Cu" signal "GND1")
		(10 "In4.Cu" signal "IN2")
		(12 "In5.Cu" signal "GND2")
		(14 "In6.Cu" signal "IN3")
		(16 "In7.Cu" signal "GND3")
		(18 "In8.Cu" signal "VCC")
		(20 "In9.Cu" signal "VCC1")
		(22 "In10.Cu" signal "GND4")
		(24 "In11.Cu" signal "IN4")
		(26 "In12.Cu" signal "GND5")
		(28 "In13.Cu" signal "IN5")
		(30 "In14.Cu" signal "GND6")
		(32 "In15.Cu" signal "IN6")
		(34 "In16.Cu" signal "GND7")
		(2 "B.Cu" signal "BOTTOM")
		(9 "F.Adhes" user "F.Adhesive")
		(11 "B.Adhes" user "B.Adhesive")
		(13 "F.Paste" user "Package Geometry/Pastemask Top")
		(15 "B.Paste" user "Package Geometry/Pastemask Bottom")
		(5 "F.SilkS" user "Ref Des/Silkscreen Top")
		(7 "B.SilkS" user "Ref Des/Silkscreen Bottom")
		(1 "F.Mask" user "Board Geometry/Soldermask Top")
		(3 "B.Mask" user "Board Geometry/Soldermask Bottom")
		(17 "Dwgs.User" user "User.Drawings")
		(19 "Cmts.User" user "User.Comments")
		(21 "Eco1.User" user "User.Eco1")
		(23 "Eco2.User" user "User.Eco2")
		(25 "Edge.Cuts" user "Board Geometry/Outline")
		(27 "Margin" user)
		(31 "F.CrtYd" user "Package Geometry/Place Bound Top")
		(29 "B.CrtYd" user "Package Geometry/Place Bound Bottom")
		(35 "F.Fab" user "Ref Des/Assembly Top")
		(33 "B.Fab" user "Ref Des/Assembly Bottom")
	)
	(footprint ""
		(layer "F.Cu")
		(at 352.270314 -255.053846 90)
		(property "Reference" "C982"
			(at 0 0 90)
			(layer "F.SilkS")
			(hide yes)
			(effects
				(font
					(size 1.27 1.27)
				)
			)
		)
		(property "Value" ""
			(at 0 0 90)
			(layer "F.Fab")
			(effects
				(font
					(size 1.27 1.27)
				)
			)
		)
		(duplicate_pad_numbers_are_jumpers no)
		(fp_line
			(start 0.7874 -0.4064)
			(end 0.7874 0.4064)
			(stroke
				(width 0.1524)
				(type default)
			)
			(layer "F.SilkS")
		)
		(fp_line
			(start -0.7874 -0.4064)
			(end 0.7874 -0.4064)
			(stroke
				(width 0.1524)
				(type default)
			)
			(layer "F.SilkS")
		)
		(fp_line
			(start 0.7874 0.4064)
			(end -0.7874 0.4064)
			(stroke
				(width 0.1524)
				(type default)
			)
			(layer "F.SilkS")
		)
		(fp_line
			(start -0.7874 0.4064)
			(end -0.7874 -0.4064)
			(stroke
				(width 0.1524)
				(type default)
			)
			(layer "F.SilkS")
		)
		(fp_line
			(start -0.12065 -0.305054)
			(end -0.12065 -0.2794)
			(stroke
				(width 0.1)
				(type default)
			)
			(layer "F.Fab")
		)
		(fp_line
			(start -0.67945 -0.305054)
			(end -0.12065 -0.305054)
			(stroke
				(width 0.1)
				(type default)
			)
			(layer "F.Fab")
		)
		(fp_line
			(start 0.67945 -0.3048)
			(end 0.67945 0.3048)
			(stroke
				(width 0.1)
				(type default)
			)
			(layer "F.Fab")
		)
		(fp_line
			(start 0.12065 -0.3048)
			(end 0.67945 -0.3048)
			(stroke
				(width 0.1)
				(type default)
			)
			(layer "F.Fab")
		)
		(fp_line
			(start 0.12065 -0.2794)
			(end 0.12065 -0.3048)
			(stroke
				(width 0.1)
				(type default)
			)
			(layer "F.Fab")
		)
		(fp_line
			(start -0.12065 -0.2794)
			(end 0.12065 -0.2794)
			(stroke
				(width 0.1)
				(type default)
			)
			(layer "F.Fab")
		)
		(fp_line
			(start 0.120396 0.2794)
			(end -0.12065 0.2794)
			(stroke
				(width 0.1)
				(type default)
			)
			(layer "F.Fab")
		)
		(fp_line
			(start -0.12065 0.2794)
			(end -0.12065 0.3048)
			(stroke
				(width 0.1)
				(type default)
			)
			(layer "F.Fab")
		)
		(fp_line
			(start 0.67945 0.3048)
			(end 0.120396 0.3048)
			(stroke
				(width 0.1)
				(type default)
			)
			(layer "F.Fab")
		)
		(fp_line
			(start 0.120396 0.3048)
			(end 0.120396 0.2794)
			(stroke
				(width 0.1)
				(type default)
			)
			(layer "F.Fab")
		)
		(fp_line
			(start -0.12065 0.3048)
			(end -0.67945 0.3048)
			(stroke
				(width 0.1)
				(type default)
			)
			(layer "F.Fab")
		)
		(fp_line
			(start -0.67945 0.3048)
			(end -0.67945 -0.305054)
			(stroke
				(width 0.1)
				(type default)
			)
			(layer "F.Fab")
		)
		(pad "1" smd circle
			(at -0.40005 0 90)
			(size 0 0)
			(layers "F.Cu" "F.Mask" "F.Paste")
			(net "PVCCIN_CPU0")
		)
		(pad "2" smd circle
			(at 0.40005 0 90)
			(size 0 0)
			(layers "F.Cu" "F.Mask" "F.Paste")
			(net "GND")
		)
	)
	(footprint ""
		(layer "F.Cu")
		(at 201.00036 -119.344948 180)
		(property "Reference" "R735"
			(at 0 0 180)
			(layer "F.SilkS")
			(hide yes)
			(effects
				(font
					(size 1.27 1.27)
				)
			)
		)
		(property "Value" ""
			(at 0 0 180)
			(layer "F.Fab")
			(effects
				(font
					(size 1.27 1.27)
				)
			)
		)
		(duplicate_pad_numbers_are_jumpers no)
		(fp_line
			(start 0.7874 0.4064)
			(end -0.7874 0.4064)
			(stroke
				(width 0.1524)
				(type default)
			)
			(layer "F.SilkS")
		)
		(fp_line
			(start 0.7874 -0.4064)
			(end 0.7874 0.4064)
			(stroke
				(width 0.1524)
				(type default)
			)
			(layer "F.SilkS")
		)
		(fp_line
			(start -0.7874 0.4064)
			(end -0.7874 -0.4064)
			(stroke
				(width 0.1524)
				(type default)
			)
			(layer "F.SilkS")
		)
		(fp_line
			(start -0.7874 -0.4064)
			(end 0.7874 -0.4064)
			(stroke
				(width 0.1524)
				(type default)
			)
			(layer "F.SilkS")
		)
		(fp_line
			(start 0.67945 0.3048)
			(end 0.120396 0.3048)
			(stroke
				(width 0.1)
				(type default)
			)
			(layer "F.Fab")
		)
		(fp_line
			(start 0.67945 -0.3048)
			(end 0.67945 0.3048)
			(stroke
				(width 0.1)
				(type default)
			)
			(layer "F.Fab")
		)
		(fp_line
			(start 0.12065 -0.2794)
			(end 0.12065 -0.3048)
			(stroke
				(width 0.1)
				(type default)
			)
			(layer "F.Fab")
		)
		(fp_line
			(start 0.12065 -0.3048)
			(end 0.67945 -0.3048)
			(stroke
				(width 0.1)
				(type default)
			)
			(layer "F.Fab")
		)
		(fp_line
			(start 0.120396 0.3048)
			(end 0.120396 0.2794)
			(stroke
				(width 0.1)
				(type default)
			)
			(layer "F.Fab")
		)
		(fp_line
			(start 0.120396 0.2794)
			(end -0.12065 0.2794)
			(stroke
				(width 0.1)
				(type default)
			)
			(layer "F.Fab")
		)
		(fp_line
			(start -0.12065 0.3048)
			(end -0.67945 0.3048)
			(stroke
				(width 0.1)
				(type default)
			)
			(layer "F.Fab")
		)
		(fp_line
			(start -0.12065 0.2794)
			(end -0.12065 0.3048)
			(stroke
				(width 0.1)
				(type default)
			)
			(layer "F.Fab")
		)
		(fp_line
			(start -0.12065 -0.2794)
			(end 0.12065 -0.2794)
			(stroke
				(width 0.1)
				(type default)
			)
			(layer "F.Fab")
		)
		(fp_line
			(start -0.12065 -0.305054)
			(end -0.12065 -0.2794)
			(stroke
				(width 0.1)
				(type default)
			)
			(layer "F.Fab")
		)
		(fp_line
			(start -0.67945 0.3048)
			(end -0.67945 -0.305054)
			(stroke
				(width 0.1)
				(type default)
			)
			(layer "F.Fab")
		)
		(fp_line
			(start -0.67945 -0.305054)
			(end -0.12065 -0.305054)
			(stroke
				(width 0.1)
				(type default)
			)
			(layer "F.Fab")
		)
		(pad "1" smd circle
			(at -0.40005 0 180)
			(size 0 0)
			(layers "F.Cu" "F.Mask" "F.Paste")
			(net "P3V3_AUX")
		)
		(pad "2" smd circle
			(at 0.40005 0 180)
			(size 0 0)
			(layers "F.Cu" "F.Mask" "F.Paste")
			(net "FM_DIMM_12V_CPS_SX_N")
		)
	)
)
